(kicad_pcb
	(version 20241229)
	(generator "pcbnew")
	(generator_version "9.0")
	(general
		(thickness 1.61)
		(legacy_teardrops no)
	)
	(paper "A3")
	(title_block
		(title "RDIMM DDR5 Tester")
		(date "2026-05-21")
		(rev "2.2.0")
		(company "Antmicro")
		(comment 9 "footprints 102-106 of 796")
	)
	(layers
		(0 "F.Cu" signal)
		(4 "In1.Cu" power)
		(6 "In2.Cu" mixed)
		(8 "In3.Cu" power)
		(10 "In4.Cu" mixed)
		(12 "In5.Cu" power)
		(14 "In6.Cu" mixed)
		(16 "In7.Cu" power)
		(18 "In8.Cu" power)
		(20 "In9.Cu" mixed)
		(22 "In10.Cu" power)
		(2 "B.Cu" signal)
		(9 "F.Adhes" user "F.Adhesive")
		(11 "B.Adhes" user "B.Adhesive")
		(13 "F.Paste" user)
		(15 "B.Paste" user)
		(5 "F.SilkS" user "F.Silkscreen")
		(7 "B.SilkS" user "B.Silkscreen")
		(1 "F.Mask" user)
		(3 "B.Mask" user)
		(17 "Dwgs.User" user "User.Drawings")
		(19 "Cmts.User" user "User.Comments")
		(21 "Eco1.User" user "User.Eco1")
		(23 "Eco2.User" user "User.Eco2")
		(25 "Edge.Cuts" user)
		(27 "Margin" user)
		(31 "F.CrtYd" user "F.Courtyard")
		(29 "B.CrtYd" user "B.Courtyard")
		(35 "F.Fab" user)
		(33 "B.Fab" user)
	)
	(footprint "antmicro-footprints:C_0402_1005Metric"
		(layer "F.Cu")
		(at 160.1 157.199999 90)
		(descr "Capacitor SMD 0402")
		(tags "capacitor SMD 0402")
		(property "Reference" "C287"
			(at 0.96 1.23 90)
			(layer "F.SilkS")
			(effects
				(font
					(size 0.7 0.7)
					(thickness 0.15)
				)
				(justify left bottom)
			)
		)
		(property "Value" "C_100n_0402"
			(at -1.022927 2.155213 90)
			(layer "F.Fab")
			(effects
				(font
					(size 0.7 0.7)
					(thickness 0.15)
				)
				(justify left bottom)
			)
		)
		(property "Datasheet" "https://www.murata.com/products/productdetail?partno=GRM155R61H104KE14%23"
			(at 0 0 90)
			(layer "F.Fab")
			(hide yes)
			(effects
				(font
					(size 1.27 1.27)
					(thickness 0.15)
				)
			)
		)
		(property "MPN" "GRM155R61H104KE14D"
			(at 0 0 90)
			(unlocked yes)
			(layer "F.Fab")
			(hide yes)
			(effects
				(font
					(size 1 1)
					(thickness 0.15)
				)
			)
		)
		(property "Manufacturer" "Murata"
			(at 0 0 90)
			(unlocked yes)
			(layer "F.Fab")
			(hide yes)
			(effects
				(font
					(size 1 1)
					(thickness 0.15)
				)
			)
		)
		(property "License" "Apache-2.0"
			(at 0 0 90)
			(unlocked yes)
			(layer "F.Fab")
			(hide yes)
			(effects
				(font
					(size 1 1)
					(thickness 0.15)
				)
			)
		)
		(property "Author" "Antmicro"
			(at 0 0 90)
			(unlocked yes)
			(layer "F.Fab")
			(hide yes)
			(effects
				(font
					(size 1 1)
					(thickness 0.15)
				)
			)
		)
		(property "Val" "100n"
			(at 0 0 90)
			(unlocked yes)
			(layer "F.Fab")
			(hide yes)
			(effects
				(font
					(size 1 1)
					(thickness 0.15)
				)
			)
		)
		(property "Voltage" "50V"
			(at 0 0 90)
			(unlocked yes)
			(layer "F.Fab")
			(hide yes)
			(effects
				(font
					(size 1 1)
					(thickness 0.15)
				)
			)
		)
		(property "Dielectric" "X5R"
			(at 0 0 90)
			(unlocked yes)
			(layer "F.Fab")
			(hide yes)
			(effects
				(font
					(size 1 1)
					(thickness 0.15)
				)
			)
		)
		(property "Public" ""
			(at 0 0 90)
			(unlocked yes)
			(layer "F.Fab")
			(hide yes)
			(effects
				(font
					(size 1 1)
					(thickness 0.15)
				)
			)
		)
		(sheetname "/FPGA MGT Interface/")
		(sheetfile "fpga-mgt.kicad_sch")
		(attr smd)
		(fp_rect
			(start -0.925 -0.47)
			(end 0.925 0.47)
			(stroke
				(width 0.05)
				(type default)
			)
			(fill no)
			(layer "F.CrtYd")
		)
		(fp_line
			(start 0.504 -0.25)
			(end 0.504 0.248)
			(stroke
				(width 0.15)
				(type solid)
			)
			(layer "F.Fab")
		)
		(fp_line
			(start -0.494 -0.25)
			(end 0.504 -0.25)
			(stroke
				(width 0.15)
				(type solid)
			)
			(layer "F.Fab")
		)
		(fp_line
			(start 0.504 0.248)
			(end -0.494 0.248)
			(stroke
				(width 0.15)
				(type solid)
			)
			(layer "F.Fab")
		)
		(fp_line
			(start -0.494 0.248)
			(end -0.494 -0.25)
			(stroke
				(width 0.15)
				(type solid)
			)
			(layer "F.Fab")
		)
		(fp_text user "License: Apache-2.0"
			(at -0.939 5.799 90)
			(layer "F.Fab")
			(effects
				(font
					(size 0.7 0.7)
					(thickness 0.15)
				)
				(justify left bottom)
			)
		)
		(fp_text user "Author: Antmicro"
			(at -0.939 3.399 90)
			(layer "F.Fab")
			(effects
				(font
					(size 0.7 0.7)
					(thickness 0.15)
				)
				(justify left bottom)
			)
		)
		(fp_text user "${REFERENCE}"
			(at -0.939 4.599 90)
			(layer "F.Fab")
			(effects
				(font
					(size 0.7 0.7)
					(thickness 0.15)
				)
				(justify left bottom)
			)
		)
		(pad "1" smd roundrect
			(at -0.48 0 90)
			(size 0.59 0.64)
			(layers "F.Cu" "F.Mask" "F.Paste")
			(roundrect_rratio 0.25)
			(net 151 "+3V3")
			(pintype "passive")
		)
		(pad "2" smd roundrect
			(at 0.48 0 90)
			(size 0.59 0.64)
			(layers "F.Cu" "F.Mask" "F.Paste")
			(roundrect_rratio 0.25)
			(net 1 "GND")
			(pintype "passive")
		)
	)
	(footprint "antmicro-footprints:R_0402_1005Metric"
		(layer "F.Cu")
		(at 135.824499 183.264 90)
		(descr "Resistor SMD 0402")
		(tags "resistor SMD 0402")
		(property "Reference" "R64"
			(at -1.036 -1.524499 90)
			(layer "F.SilkS")
			(effects
				(font
					(size 0.7 0.7)
					(thickness 0.15)
				)
				(justify left bottom)
			)
		)
		(property "Value" "R_330R_0402"
			(at -1.011843 1.772047 90)
			(layer "F.Fab")
			(effects
				(font
					(size 0.7 0.7)
					(thickness 0.15)
				)
				(justify left bottom)
			)
		)
		(property "Datasheet" "https://www.bourns.com/docs/product-datasheets/cr.pdf"
			(at 0 0 90)
			(layer "F.Fab")
			(hide yes)
			(effects
				(font
					(size 1.27 1.27)
					(thickness 0.15)
				)
			)
		)
		(property "Manufacturer" "Bourns"
			(at 0 0 90)
			(unlocked yes)
			(layer "F.Fab")
			(hide yes)
			(effects
				(font
					(size 1 1)
					(thickness 0.15)
				)
			)
		)
		(property "MPN" "CR0402-FX-3300GLF"
			(at 0 0 90)
			(unlocked yes)
			(layer "F.Fab")
			(hide yes)
			(effects
				(font
					(size 1 1)
					(thickness 0.15)
				)
			)
		)
		(property "Val" "330R"
			(at 0 0 90)
			(unlocked yes)
			(layer "F.Fab")
			(hide yes)
			(effects
				(font
					(size 1 1)
					(thickness 0.15)
				)
			)
		)
		(property "License" "Apache-2.0"
			(at 0 0 90)
			(unlocked yes)
			(layer "F.Fab")
			(hide yes)
			(effects
				(font
					(size 1 1)
					(thickness 0.15)
				)
			)
		)
		(property "Author" "Antmicro"
			(at 0 0 90)
			(unlocked yes)
			(layer "F.Fab")
			(hide yes)
			(effects
				(font
					(size 1 1)
					(thickness 0.15)
				)
			)
		)
		(property "Tolerance" "1%"
			(at 0 0 90)
			(unlocked yes)
			(layer "F.Fab")
			(hide yes)
			(effects
				(font
					(size 1 1)
					(thickness 0.15)
				)
			)
		)
		(sheetname "/Debug FTDI + VNA/")
		(sheetfile "debug-ftdi.kicad_sch")
		(attr smd)
		(fp_rect
			(start -0.925 -0.47)
			(end 0.925 0.47)
			(stroke
				(width 0.05)
				(type default)
			)
			(fill no)
			(layer "F.CrtYd")
		)
		(fp_rect
			(start -0.5 -0.25)
			(end 0.5 0.25)
			(stroke
				(width 0.15)
				(type solid)
			)
			(fill no)
			(layer "F.Fab")
		)
		(fp_text user "Author: Antmicro"
			(at -0.95 4.169 90)
			(layer "F.Fab")
			(effects
				(font
					(size 0.7 0.7)
					(thickness 0.15)
				)
				(justify left bottom)
			)
		)
		(fp_text user "License: Apache-2.0"
			(at -0.95 5.169 90)
			(layer "F.Fab")
			(effects
				(font
					(size 0.7 0.7)
					(thickness 0.15)
				)
				(justify left bottom)
			)
		)
		(fp_text user "${REFERENCE}"
			(at -0.95 3.168 90)
			(layer "F.Fab")
			(effects
				(font
					(size 0.7 0.7)
					(thickness 0.15)
				)
				(justify left bottom)
			)
		)
		(pad "1" smd roundrect
			(at -0.48 0 90)
			(size 0.59 0.64)
			(layers "F.Cu" "F.Mask" "F.Paste")
			(roundrect_rratio 0.25)
			(net 39 "Net-(D10-A)")
			(pintype "passive")
		)
		(pad "2" smd roundrect
			(at 0.48 0 90)
			(size 0.59 0.64)
			(layers "F.Cu" "F.Mask" "F.Paste")
			(roundrect_rratio 0.25)
			(net 443 "/Debug FTDI + VNA/LED_TX0")
			(pintype "passive")
		)
	)
	(footprint "antmicro-footprints:C_0402_1005Metric"
		(layer "F.Cu")
		(at 230.2 161.35 90)
		(descr "Capacitor SMD 0402")
		(tags "capacitor SMD 0402")
		(property "Reference" "C198"
			(at -2.35 2.07 90)
			(layer "F.SilkS")
			(effects
				(font
					(size 0.7 0.7)
					(thickness 0.15)
				)
				(justify left bottom)
			)
		)
		(property "Value" "C_1u_0402"
			(at -4.564428 51.328713 90)
			(layer "F.Fab")
			(effects
				(font
					(size 0.7 0.7)
					(thickness 0.15)
				)
				(justify left bottom)
			)
		)
		(property "Datasheet" "https://product.tdk.com/en/search/capacitor/ceramic/mlcc/info?part_no=C1005X6S1A105K050BC"
			(at 0 0 90)
			(layer "F.Fab")
			(hide yes)
			(effects
				(font
					(size 1.27 1.27)
					(thickness 0.15)
				)
			)
		)
		(property "Manufacturer" "TDK"
			(at 0 0 90)
			(unlocked yes)
			(layer "F.Fab")
			(hide yes)
			(effects
				(font
					(size 1 1)
					(thickness 0.15)
				)
			)
		)
		(property "MPN" "C1005X6S1A105K050BC"
			(at 0 0 90)
			(unlocked yes)
			(layer "F.Fab")
			(hide yes)
			(effects
				(font
					(size 1 1)
					(thickness 0.15)
				)
			)
		)
		(property "Val" "1u"
			(at 0 0 90)
			(unlocked yes)
			(layer "F.Fab")
			(hide yes)
			(effects
				(font
					(size 1 1)
					(thickness 0.15)
				)
			)
		)
		(property "License" "Apache-2.0"
			(at 0 0 90)
			(unlocked yes)
			(layer "F.Fab")
			(hide yes)
			(effects
				(font
					(size 1 1)
					(thickness 0.15)
				)
			)
		)
		(property "Author" "Antmicro"
			(at 0 0 90)
			(unlocked yes)
			(layer "F.Fab")
			(hide yes)
			(effects
				(font
					(size 1 1)
					(thickness 0.15)
				)
			)
		)
		(property "Voltage" ""
			(at 0 0 90)
			(unlocked yes)
			(layer "F.Fab")
			(hide yes)
			(effects
				(font
					(size 1 1)
					(thickness 0.15)
				)
			)
		)
		(property "Dielectric" ""
			(at 0 0 90)
			(unlocked yes)
			(layer "F.Fab")
			(hide yes)
			(effects
				(font
					(size 1 1)
					(thickness 0.15)
				)
			)
		)
		(sheetname "/Supply/")
		(sheetfile "supply.kicad_sch")
		(attr smd)
		(fp_rect
			(start -0.925 -0.47)
			(end 0.925 0.47)
			(stroke
				(width 0.05)
				(type default)
			)
			(fill no)
			(layer "F.CrtYd")
		)
		(fp_line
			(start 0.504 -0.25)
			(end 0.504 0.248)
			(stroke
				(width 0.15)
				(type solid)
			)
			(layer "F.Fab")
		)
		(fp_line
			(start -0.494 -0.25)
			(end 0.504 -0.25)
			(stroke
				(width 0.15)
				(type solid)
			)
			(layer "F.Fab")
		)
		(fp_line
			(start 0.504 0.248)
			(end -0.494 0.248)
			(stroke
				(width 0.15)
				(type solid)
			)
			(layer "F.Fab")
		)
		(fp_line
			(start -0.494 0.248)
			(end -0.494 -0.25)
			(stroke
				(width 0.15)
				(type solid)
			)
			(layer "F.Fab")
		)
		(fp_text user "Author: Antmicro"
			(at -0.939 3.399 90)
			(layer "F.Fab")
			(effects
				(font
					(size 0.7 0.7)
					(thickness 0.15)
				)
				(justify left bottom)
			)
		)
		(fp_text user "License: Apache-2.0"
			(at -0.939 5.799 90)
			(layer "F.Fab")
			(effects
				(font
					(size 0.7 0.7)
					(thickness 0.15)
				)
				(justify left bottom)
			)
		)
		(fp_text user "${REFERENCE}"
			(at -0.939 4.599 90)
			(layer "F.Fab")
			(effects
				(font
					(size 0.7 0.7)
					(thickness 0.15)
				)
				(justify left bottom)
			)
		)
		(pad "1" smd roundrect
			(at -0.48 0 90)
			(size 0.59 0.64)
			(layers "F.Cu" "F.Mask" "F.Paste")
			(roundrect_rratio 0.25)
			(net 1 "GND")
			(pintype "passive")
		)
		(pad "2" smd roundrect
			(at 0.48 0 90)
			(size 0.59 0.64)
			(layers "F.Cu" "F.Mask" "F.Paste")
			(roundrect_rratio 0.25)
			(net 152 "+5V")
			(pintype "passive")
		)
	)
	(footprint "antmicro-footprints:C_0402_1005Metric"
		(layer "F.Cu")
		(at 241.774499 185.099 -90)
		(descr "Capacitor SMD 0402")
		(tags "capacitor SMD 0402")
		(property "Reference" "C196"
			(at -1.199 -1.575501 90)
			(layer "F.SilkS")
			(effects
				(font
					(size 0.7 0.7)
					(thickness 0.15)
				)
				(justify right bottom)
			)
		)
		(property "Value" "C_100n_0402"
			(at -1.022927 2.155213 90)
			(layer "F.Fab")
			(effects
				(font
					(size 0.7 0.7)
					(thickness 0.15)
				)
				(justify right bottom)
			)
		)
		(property "Datasheet" "https://www.murata.com/products/productdetail?partno=GRM155R61H104KE14%23"
			(at 0 0 270)
			(layer "F.Fab")
			(hide yes)
			(effects
				(font
					(size 1.27 1.27)
					(thickness 0.15)
				)
			)
		)
		(property "Manufacturer" "Murata"
			(at 0 0 270)
			(unlocked yes)
			(layer "F.Fab")
			(hide yes)
			(effects
				(font
					(size 1 1)
					(thickness 0.15)
				)
			)
		)
		(property "MPN" "GRM155R61H104KE14D"
			(at 0 0 270)
			(unlocked yes)
			(layer "F.Fab")
			(hide yes)
			(effects
				(font
					(size 1 1)
					(thickness 0.15)
				)
			)
		)
		(property "Val" "100n"
			(at 0 0 270)
			(unlocked yes)
			(layer "F.Fab")
			(hide yes)
			(effects
				(font
					(size 1 1)
					(thickness 0.15)
				)
			)
		)
		(property "License" "Apache-2.0"
			(at 0 0 270)
			(unlocked yes)
			(layer "F.Fab")
			(hide yes)
			(effects
				(font
					(size 1 1)
					(thickness 0.15)
				)
			)
		)
		(property "Author" "Antmicro"
			(at 0 0 270)
			(unlocked yes)
			(layer "F.Fab")
			(hide yes)
			(effects
				(font
					(size 1 1)
					(thickness 0.15)
				)
			)
		)
		(property "Voltage" "50V"
			(at 0 0 270)
			(unlocked yes)
			(layer "F.Fab")
			(hide yes)
			(effects
				(font
					(size 1 1)
					(thickness 0.15)
				)
			)
		)
		(property "Dielectric" "X5R"
			(at 0 0 270)
			(unlocked yes)
			(layer "F.Fab")
			(hide yes)
			(effects
				(font
					(size 1 1)
					(thickness 0.15)
				)
			)
		)
		(sheetname "/I^{2}C + I3C/")
		(sheetfile "i2c.kicad_sch")
		(attr smd)
		(fp_rect
			(start -0.925 -0.47)
			(end 0.925 0.47)
			(stroke
				(width 0.05)
				(type default)
			)
			(fill no)
			(layer "F.CrtYd")
		)
		(fp_line
			(start -0.494 0.248)
			(end -0.494 -0.25)
			(stroke
				(width 0.15)
				(type solid)
			)
			(layer "F.Fab")
		)
		(fp_line
			(start 0.504 0.248)
			(end -0.494 0.248)
			(stroke
				(width 0.15)
				(type solid)
			)
			(layer "F.Fab")
		)
		(fp_line
			(start -0.494 -0.25)
			(end 0.504 -0.25)
			(stroke
				(width 0.15)
				(type solid)
			)
			(layer "F.Fab")
		)
		(fp_line
			(start 0.504 -0.25)
			(end 0.504 0.248)
			(stroke
				(width 0.15)
				(type solid)
			)
			(layer "F.Fab")
		)
		(fp_text user "${REFERENCE}"
			(at -0.939 4.599 270)
			(layer "F.Fab")
			(effects
				(font
					(size 0.7 0.7)
					(thickness 0.15)
				)
				(justify left bottom)
			)
		)
		(fp_text user "Author: Antmicro"
			(at -0.939 3.399 270)
			(layer "F.Fab")
			(effects
				(font
					(size 0.7 0.7)
					(thickness 0.15)
				)
				(justify left bottom)
			)
		)
		(fp_text user "License: Apache-2.0"
			(at -0.939 5.799 270)
			(layer "F.Fab")
			(effects
				(font
					(size 0.7 0.7)
					(thickness 0.15)
				)
				(justify left bottom)
			)
		)
		(pad "1" smd roundrect
			(at -0.48 0 270)
			(size 0.59 0.64)
			(layers "F.Cu" "F.Mask" "F.Paste")
			(roundrect_rratio 0.25)
			(net 1 "GND")
			(pintype "passive")
		)
		(pad "2" smd roundrect
			(at 0.48 0 270)
			(size 0.59 0.64)
			(layers "F.Cu" "F.Mask" "F.Paste")
			(roundrect_rratio 0.25)
			(net 38 "+3V3_AON")
			(pintype "passive")
		)
	)
	(footprint "antmicro-footprints:C_0402_1005Metric"
		(layer "F.Cu")
		(at 241.774499 181.349 -90)
		(descr "Capacitor SMD 0402")
		(tags "capacitor SMD 0402")
		(property "Reference" "C197"
			(at -1.049 -1.525501 90)
			(layer "F.SilkS")
			(effects
				(font
					(size 0.7 0.7)
					(thickness 0.15)
				)
				(justify right bottom)
			)
		)
		(property "Value" "C_100n_0402"
			(at -1.022927 2.155213 90)
			(layer "F.Fab")
			(effects
				(font
					(size 0.7 0.7)
					(thickness 0.15)
				)
				(justify right bottom)
			)
		)
		(property "Datasheet" "https://www.murata.com/products/productdetail?partno=GRM155R61H104KE14%23"
			(at 0 0 270)
			(layer "F.Fab")
			(hide yes)
			(effects
				(font
					(size 1.27 1.27)
					(thickness 0.15)
				)
			)
		)
		(property "Manufacturer" "Murata"
			(at 0 0 270)
			(unlocked yes)
			(layer "F.Fab")
			(hide yes)
			(effects
				(font
					(size 1 1)
					(thickness 0.15)
				)
			)
		)
		(property "MPN" "GRM155R61H104KE14D"
			(at 0 0 270)
			(unlocked yes)
			(layer "F.Fab")
			(hide yes)
			(effects
				(font
					(size 1 1)
					(thickness 0.15)
				)
			)
		)
		(property "Val" "100n"
			(at 0 0 270)
			(unlocked yes)
			(layer "F.Fab")
			(hide yes)
			(effects
				(font
					(size 1 1)
					(thickness 0.15)
				)
			)
		)
		(property "License" "Apache-2.0"
			(at 0 0 270)
			(unlocked yes)
			(layer "F.Fab")
			(hide yes)
			(effects
				(font
					(size 1 1)
					(thickness 0.15)
				)
			)
		)
		(property "Author" "Antmicro"
			(at 0 0 270)
			(unlocked yes)
			(layer "F.Fab")
			(hide yes)
			(effects
				(font
					(size 1 1)
					(thickness 0.15)
				)
			)
		)
		(property "Voltage" "50V"
			(at 0 0 270)
			(unlocked yes)
			(layer "F.Fab")
			(hide yes)
			(effects
				(font
					(size 1 1)
					(thickness 0.15)
				)
			)
		)
		(property "Dielectric" "X5R"
			(at 0 0 270)
			(unlocked yes)
			(layer "F.Fab")
			(hide yes)
			(effects
				(font
					(size 1 1)
					(thickness 0.15)
				)
			)
		)
		(sheetname "/I^{2}C + I3C/")
		(sheetfile "i2c.kicad_sch")
		(attr smd)
		(fp_rect
			(start -0.925 -0.47)
			(end 0.925 0.47)
			(stroke
				(width 0.05)
				(type default)
			)
			(fill no)
			(layer "F.CrtYd")
		)
		(fp_line
			(start -0.494 0.248)
			(end -0.494 -0.25)
			(stroke
				(width 0.15)
				(type solid)
			)
			(layer "F.Fab")
		)
		(fp_line
			(start 0.504 0.248)
			(end -0.494 0.248)
			(stroke
				(width 0.15)
				(type solid)
			)
			(layer "F.Fab")
		)
		(fp_line
			(start -0.494 -0.25)
			(end 0.504 -0.25)
			(stroke
				(width 0.15)
				(type solid)
			)
			(layer "F.Fab")
		)
		(fp_line
			(start 0.504 -0.25)
			(end 0.504 0.248)
			(stroke
				(width 0.15)
				(type solid)
			)
			(layer "F.Fab")
		)
		(fp_text user "License: Apache-2.0"
			(at -0.939 5.799 270)
			(layer "F.Fab")
			(effects
				(font
					(size 0.7 0.7)
					(thickness 0.15)
				)
				(justify left bottom)
			)
		)
		(fp_text user "${REFERENCE}"
			(at -0.939 4.599 270)
			(layer "F.Fab")
			(effects
				(font
					(size 0.7 0.7)
					(thickness 0.15)
				)
				(justify left bottom)
			)
		)
		(fp_text user "Author: Antmicro"
			(at -0.939 3.399 270)
			(layer "F.Fab")
			(effects
				(font
					(size 0.7 0.7)
					(thickness 0.15)
				)
				(justify left bottom)
			)
		)
		(pad "1" smd roundrect
			(at -0.48 0 270)
			(size 0.59 0.64)
			(layers "F.Cu" "F.Mask" "F.Paste")
			(roundrect_rratio 0.25)
			(net 1 "GND")
			(pintype "passive")
		)
		(pad "2" smd roundrect
			(at 0.48 0 270)
			(size 0.59 0.64)
			(layers "F.Cu" "F.Mask" "F.Paste")
			(roundrect_rratio 0.25)
			(net 38 "+3V3_AON")
			(pintype "passive")
		)
	)
)
